(kicad_pcb
	(version 20260206)
	(generator "pcbnew")
	(generator_version "10.0")
	(general
		(thickness 1.6)
		(legacy_teardrops no)
	)
	(paper "A4")
	(title_block
		(title "Bryce Canyon_Front Panel_16369-1_OCP.brd")
		(comment 1 "Bryce Canyon / footprints 56-62 of 154")
	)
	(layers
		(0 "F.Cu" signal "TOP")
		(4 "In1.Cu" signal "L2GND")
		(6 "In2.Cu" signal "L3VCC")
		(2 "B.Cu" signal "BOTTOM")
		(9 "F.Adhes" user "F.Adhesive")
		(11 "B.Adhes" user "B.Adhesive")
		(13 "F.Paste" user "Package Geometry/Pastemask Top")
		(15 "B.Paste" user "Package Geometry/Pastemask Bottom")
		(5 "F.SilkS" user "Ref Des/Silkscreen Top")
		(7 "B.SilkS" user "Ref Des/Silkscreen Bottom")
		(1 "F.Mask" user "Board Geometry/Soldermask Top")
		(3 "B.Mask" user "Board Geometry/Soldermask Bottom")
		(17 "Dwgs.User" user "User.Drawings")
		(19 "Cmts.User" user "User.Comments")
		(21 "Eco1.User" user "User.Eco1")
		(23 "Eco2.User" user "User.Eco2")
		(25 "Edge.Cuts" user "Board Geometry/Outline")
		(27 "Margin" user)
		(31 "F.CrtYd" user "Package Geometry/Place Bound Top")
		(29 "B.CrtYd" user "Package Geometry/Place Bound Bottom")
		(35 "F.Fab" user "Ref Des/Assembly Top")
		(33 "B.Fab" user "Ref Des/Assembly Bottom")
	)
	(footprint ""
		(layer "F.Cu")
		(at 7.690866 -28.004008 90)
		(property "Reference" "U5"
			(at 0 0 90)
			(layer "F.SilkS")
			(hide yes)
			(effects
				(font
					(size 1.27 1.27)
				)
			)
		)
		(property "Value" "TPS3422EGDRYR-GP"
			(at -0.1016 -5.4229 90)
			(unlocked yes)
			(layer "F.Fab")
			(hide yes)
			(effects
				(font
					(size 1.016 1.016)
					(thickness 0.1524)
				)
			)
		)
		(property "Device Type" "XSON6H24"
			(at -0.1016 -6.9469 90)
			(unlocked yes)
			(layer "F.Fab")
			(hide yes)
			(effects
				(font
					(size 1.016 1.016)
					(thickness 0.1524)
				)
			)
		)
		(duplicate_pad_numbers_are_jumpers no)
		(fp_line
			(start -0.7239 -0.762)
			(end -0.7239 -0.9398)
			(stroke
				(width 0.1524)
				(type default)
			)
			(layer "F.SilkS")
		)
		(fp_line
			(start -0.9779 -0.508)
			(end -0.7239 -0.762)
			(stroke
				(width 0.1524)
				(type default)
			)
			(layer "F.SilkS")
		)
		(fp_line
			(start -1.1557 -0.508)
			(end -0.9779 -0.508)
			(stroke
				(width 0.1524)
				(type default)
			)
			(layer "F.SilkS")
		)
		(fp_line
			(start 0.9779 0.508)
			(end 1.1557 0.508)
			(stroke
				(width 0.1524)
				(type default)
			)
			(layer "F.SilkS")
		)
		(fp_line
			(start -0.9779 0.508)
			(end -0.7239 0.762)
			(stroke
				(width 0.1524)
				(type default)
			)
			(layer "F.SilkS")
		)
		(fp_line
			(start -1.1557 0.508)
			(end -0.9779 0.508)
			(stroke
				(width 0.1524)
				(type default)
			)
			(layer "F.SilkS")
		)
		(fp_line
			(start 0.7239 0.762)
			(end 0.9779 0.508)
			(stroke
				(width 0.1524)
				(type default)
			)
			(layer "F.SilkS")
		)
		(fp_line
			(start -0.7239 0.762)
			(end -0.7239 0.9398)
			(stroke
				(width 0.1524)
				(type default)
			)
			(layer "F.SilkS")
		)
		(fp_line
			(start 0.7239 0.9398)
			(end 0.7239 0.762)
			(stroke
				(width 0.1524)
				(type default)
			)
			(layer "F.SilkS")
		)
		(fp_poly
			(pts
				(xy 0.846328 -0.607314) (xy 0.846328 -1.016) (xy 1.2319 -0.607314)
			)
			(stroke
				(width 0)
				(type default)
			)
			(fill yes)
			(layer "F.SilkS")
		)
		(fp_rect
			(start -0.7239 0.508)
			(end 0.7239 -0.508)
			(stroke
				(width 0)
				(type default)
			)
			(fill no)
			(layer "F.CrtYd")
		)
		(fp_poly
			(pts
				(xy -1.2319 1.016) (xy -1.2319 -1.016) (xy 1.2319 -1.016) (xy 1.2319 -0.0889) (xy 0.7239 -0.0889)
				(xy 0.7239 -0.508) (xy -0.7239 -0.508) (xy -0.7239 0.508) (xy 0.7239 0.508) (xy 0.7239 -0.0762)
				(xy 1.2319 -0.0762) (xy 1.2319 1.016)
			)
			(stroke
				(width 0)
				(type default)
			)
			(fill no)
			(layer "F.CrtYd")
		)
		(fp_rect
			(start -1.2319 1.016)
			(end 1.2319 -1.016)
			(stroke
				(width 0)
				(type default)
			)
			(fill no)
			(layer "F.Fab")
		)
		(pad "1" smd rect
			(at 0.50038 -0.310134 90)
			(size 0.3048 0.381)
			(layers "F.Cu" "F.Mask" "F.Paste")
			(net "SYS_RESET_BTN_A_N_R")
		)
		(pad "2" smd rect
			(at 0 -0.310134 90)
			(size 0.3048 0.381)
			(layers "F.Cu" "F.Mask" "F.Paste")
			(net "GND")
		)
		(pad "3" smd rect
			(at -0.50038 -0.310134 90)
			(size 0.3048 0.381)
			(layers "F.Cu" "F.Mask" "F.Paste")
			(net "SYS_RESET_BTN_A")
		)
		(pad "4" smd rect
			(at -0.50038 0.310134 90)
			(size 0.3048 0.381)
			(layers "F.Cu" "F.Mask" "F.Paste")
			(net "P3V3_STBY_A")
		)
		(pad "5" smd rect
			(at 0 0.310134 90)
			(size 0.3048 0.381)
			(layers "F.Cu" "F.Mask" "F.Paste")
			(net "RST_A_TS")
		)
		(pad "6" smd rect
			(at 0.50038 0.310134 90)
			(size 0.3048 0.381)
			(layers "F.Cu" "F.Mask" "F.Paste")
			(net "GND")
		)
	)
	(footprint ""
		(layer "F.Cu")
		(at 56.6928 -49.4284 180)
		(property "Reference" "R36"
			(at 0 0 180)
			(layer "F.SilkS")
			(hide yes)
			(effects
				(font
					(size 1.27 1.27)
				)
			)
		)
		(property "Value" "4K7R2F-GP"
			(at 0.064008 -4.679696 180)
			(unlocked yes)
			(layer "F.Fab")
			(hide yes)
			(effects
				(font
					(size 2.54 2.54)
					(thickness 0.381)
				)
			)
		)
		(property "Device Type" "R402H16"
			(at 0.064008 -6.203696 180)
			(unlocked yes)
			(layer "F.Fab")
			(hide yes)
			(effects
				(font
					(size 2.54 2.54)
					(thickness 0.381)
				)
			)
		)
		(duplicate_pad_numbers_are_jumpers no)
		(fp_line
			(start 0.508 -0.9398)
			(end -0.508 -0.9398)
			(stroke
				(width 0.1524)
				(type default)
			)
			(layer "F.SilkS")
		)
		(fp_line
			(start -0.508 -0.9398)
			(end -0.508 0.9398)
			(stroke
				(width 0.1524)
				(type default)
			)
			(layer "F.SilkS")
		)
		(fp_rect
			(start -0.508 0.9398)
			(end 0.508 -0.9398)
			(stroke
				(width 0)
				(type default)
			)
			(fill no)
			(layer "F.CrtYd")
		)
		(fp_rect
			(start -0.508 0.9398)
			(end 0.508 -0.9398)
			(stroke
				(width 0)
				(type default)
			)
			(fill no)
			(layer "F.Fab")
		)
		(pad "1" smd custom
			(at 0 -0.4445 180)
			(size 0.1397 0.1397)
			(layers "F.Cu" "F.Mask" "F.Paste")
			(net "TEMP_2_A1")
			(options
				(clearance outline)
				(anchor circle)
			)
			(primitives
				(gr_poly
					(pts
						(arc
							(start -0.1778 -0.2794)
							(mid -0.249642 -0.249642)
							(end -0.2794 -0.1778)
						)
						(arc
							(start -0.2794 0.1778)
							(mid -0.249642 0.249642)
							(end -0.1778 0.2794)
						)
						(arc
							(start 0.1778 0.2794)
							(mid 0.249642 0.249642)
							(end 0.2794 0.1778)
						)
						(arc
							(start 0.2794 -0.1778)
							(mid 0.249642 -0.249642)
							(end 0.1778 -0.2794)
						)
					)
					(width 0)
					(fill yes)
				)
			)
		)
		(pad "2" smd custom
			(at 0 0.4445 180)
			(size 0.1397 0.1397)
			(layers "F.Cu" "F.Mask" "F.Paste")
			(net "GND")
			(options
				(clearance outline)
				(anchor circle)
			)
			(primitives
				(gr_poly
					(pts
						(arc
							(start -0.1778 -0.2794)
							(mid -0.249642 -0.249642)
							(end -0.2794 -0.1778)
						)
						(arc
							(start -0.2794 0.1778)
							(mid -0.249642 0.249642)
							(end -0.1778 0.2794)
						)
						(arc
							(start 0.1778 0.2794)
							(mid 0.249642 0.249642)
							(end 0.2794 0.1778)
						)
						(arc
							(start 0.2794 -0.1778)
							(mid 0.249642 -0.249642)
							(end 0.1778 -0.2794)
						)
					)
					(width 0)
					(fill yes)
				)
			)
		)
	)
	(footprint ""
		(layer "F.Cu")
		(at 54.818534 -56.91632)
		(property "Reference" "D2"
			(at 0 0 0)
			(layer "F.SilkS")
			(hide yes)
			(effects
				(font
					(size 1.27 1.27)
				)
			)
		)
		(property "Value" "PESD3V3L4UW-GP"
			(at 2.2606 1.27 0)
			(unlocked yes)
			(layer "F.Fab")
			(hide yes)
			(effects
				(font
					(size 1.016 1.016)
					(thickness 0.1524)
				)
			)
		)
		(property "Device Type" "SOT-23-5-3H24"
			(at 2.2606 -0.254 0)
			(unlocked yes)
			(layer "F.Fab")
			(hide yes)
			(effects
				(font
					(size 1.016 1.016)
					(thickness 0.1524)
				)
			)
		)
		(duplicate_pad_numbers_are_jumpers no)
		(fp_line
			(start -1.143 0.254)
			(end -1.143 1.524)
			(stroke
				(width 0.3302)
				(type default)
			)
			(layer "F.SilkS")
		)
		(fp_line
			(start -1.143 1.524)
			(end 0.127 1.524)
			(stroke
				(width 0.3302)
				(type default)
			)
			(layer "F.SilkS")
		)
		(fp_line
			(start -1.0541 -1.4351)
			(end -1.0541 1.4351)
			(stroke
				(width 0.1524)
				(type default)
			)
			(layer "F.SilkS")
		)
		(fp_line
			(start -1.0541 1.4351)
			(end 1.0541 1.4351)
			(stroke
				(width 0.1524)
				(type default)
			)
			(layer "F.SilkS")
		)
		(fp_line
			(start 1.0541 -1.4351)
			(end -1.0541 -1.4351)
			(stroke
				(width 0.1524)
				(type default)
			)
			(layer "F.SilkS")
		)
		(fp_line
			(start 1.0541 1.4351)
			(end 1.0541 -1.4351)
			(stroke
				(width 0.1524)
				(type default)
			)
			(layer "F.SilkS")
		)
		(fp_poly
			(pts
				(xy -0.508 1.5113) (xy -0.0762 1.9431) (xy -0.9398 1.9431)
			)
			(stroke
				(width 0)
				(type default)
			)
			(fill yes)
			(layer "F.SilkS")
		)
		(fp_rect
			(start -1.3081 1.6891)
			(end 1.3081 -1.6891)
			(stroke
				(width 0)
				(type default)
			)
			(fill no)
			(layer "F.CrtYd")
		)
		(fp_rect
			(start -1.3081 1.6891)
			(end 1.3081 -1.6891)
			(stroke
				(width 0)
				(type default)
			)
			(fill no)
			(layer "F.Fab")
		)
		(pad "1" smd rect
			(at -0.500126 0.7239)
			(size 0.3048 0.9144)
			(layers "F.Cu" "F.Mask" "F.Paste")
			(net "I2C_DEBUG_B_SDA")
		)
		(pad "2" smd rect
			(at 0 0.7239)
			(size 0.3048 0.9144)
			(layers "F.Cu" "F.Mask" "F.Paste")
			(net "GND")
		)
		(pad "3" smd rect
			(at 0.500126 0.7239)
			(size 0.3048 0.9144)
			(layers "F.Cu" "F.Mask" "F.Paste")
			(net "UART_DEBUG_B_RX")
		)
		(pad "4" smd rect
			(at 0.500126 -0.7239)
			(size 0.3048 0.9144)
			(layers "F.Cu" "F.Mask" "F.Paste")
			(net "UART_DEBUG_B_TX")
		)
		(pad "5" smd rect
			(at -0.500126 -0.7239)
			(size 0.3048 0.9144)
			(layers "F.Cu" "F.Mask" "F.Paste")
			(net "I2C_DEBUG_B_SCL")
		)
	)
	(footprint ""
		(layer "F.Cu")
		(at 9.7536 -14.9352 -90)
		(property "Reference" "C5"
			(at 0 0 270)
			(layer "F.SilkS")
			(hide yes)
			(effects
				(font
					(size 1.27 1.27)
				)
			)
		)
		(property "Value" "SCD1U16V2KX-3GP"
			(at 1.1811 -3.3909 270)
			(unlocked yes)
			(layer "F.Fab")
			(hide yes)
			(effects
				(font
					(size 2.54 2.54)
					(thickness 0.381)
				)
			)
		)
		(property "Device Type" "C402H22"
			(at 1.1811 -4.9149 270)
			(unlocked yes)
			(layer "F.Fab")
			(hide yes)
			(effects
				(font
					(size 2.54 2.54)
					(thickness 0.381)
				)
			)
		)
		(duplicate_pad_numbers_are_jumpers no)
		(fp_rect
			(start -0.4318 0.9525)
			(end 0.4318 -0.9525)
			(stroke
				(width 0)
				(type default)
			)
			(fill no)
			(layer "F.CrtYd")
		)
		(fp_rect
			(start -0.4318 0.9525)
			(end 0.4318 -0.9525)
			(stroke
				(width 0)
				(type default)
			)
			(fill no)
			(layer "F.Fab")
		)
		(pad "1" smd custom
			(at 0 -0.4445 270)
			(size 0.1524 0.1524)
			(layers "F.Cu" "F.Mask" "F.Paste")
			(net "P3V3_STBY_A")
			(options
				(clearance outline)
				(anchor circle)
			)
			(primitives
				(gr_poly
					(pts
						(arc
							(start 0.3048 -0.2032)
							(mid 0.275042 -0.275042)
							(end 0.2032 -0.3048)
						)
						(arc
							(start -0.2032 -0.3048)
							(mid -0.275042 -0.275042)
							(end -0.3048 -0.2032)
						)
						(arc
							(start -0.3048 0.2032)
							(mid -0.275042 0.275042)
							(end -0.2032 0.3048)
						)
						(arc
							(start 0.2032 0.3048)
							(mid 0.275042 0.275042)
							(end 0.3048 0.2032)
						)
					)
					(width 0)
					(fill yes)
				)
			)
		)
		(pad "2" smd custom
			(at 0 0.4445 270)
			(size 0.1524 0.1524)
			(layers "F.Cu" "F.Mask" "F.Paste")
			(net "GND")
			(options
				(clearance outline)
				(anchor circle)
			)
			(primitives
				(gr_poly
					(pts
						(arc
							(start 0.3048 -0.2032)
							(mid 0.275042 -0.275042)
							(end 0.2032 -0.3048)
						)
						(arc
							(start -0.2032 -0.3048)
							(mid -0.275042 -0.275042)
							(end -0.3048 -0.2032)
						)
						(arc
							(start -0.3048 0.2032)
							(mid -0.275042 0.275042)
							(end -0.2032 0.3048)
						)
						(arc
							(start 0.2032 0.3048)
							(mid 0.275042 0.275042)
							(end 0.3048 0.2032)
						)
					)
					(width 0)
					(fill yes)
				)
			)
		)
	)
	(footprint ""
		(layer "F.Cu")
		(at 11.811 -49.68494 90)
		(property "Reference" "R32"
			(at 0 0 90)
			(layer "F.SilkS")
			(hide yes)
			(effects
				(font
					(size 1.27 1.27)
				)
			)
		)
		(property "Value" "4K7R2F-GP"
			(at 0.064008 -4.679696 90)
			(unlocked yes)
			(layer "F.Fab")
			(hide yes)
			(effects
				(font
					(size 2.54 2.54)
					(thickness 0.381)
				)
			)
		)
		(property "Device Type" "R402H16"
			(at 0.064008 -6.203696 90)
			(unlocked yes)
			(layer "F.Fab")
			(hide yes)
			(effects
				(font
					(size 2.54 2.54)
					(thickness 0.381)
				)
			)
		)
		(duplicate_pad_numbers_are_jumpers no)
		(fp_line
			(start 0.508 -0.9398)
			(end -0.508 -0.9398)
			(stroke
				(width 0.1524)
				(type default)
			)
			(layer "F.SilkS")
		)
		(fp_line
			(start -0.508 -0.9398)
			(end -0.508 0.9398)
			(stroke
				(width 0.1524)
				(type default)
			)
			(layer "F.SilkS")
		)
		(fp_rect
			(start -0.508 0.9398)
			(end 0.508 -0.9398)
			(stroke
				(width 0)
				(type default)
			)
			(fill no)
			(layer "F.CrtYd")
		)
		(fp_rect
			(start -0.508 0.9398)
			(end 0.508 -0.9398)
			(stroke
				(width 0)
				(type default)
			)
			(fill no)
			(layer "F.Fab")
		)
		(pad "1" smd custom
			(at 0 -0.4445 90)
			(size 0.1397 0.1397)
			(layers "F.Cu" "F.Mask" "F.Paste")
			(net "TEMP_1_A0")
			(options
				(clearance outline)
				(anchor circle)
			)
			(primitives
				(gr_poly
					(pts
						(arc
							(start -0.1778 -0.2794)
							(mid -0.249642 -0.249642)
							(end -0.2794 -0.1778)
						)
						(arc
							(start -0.2794 0.1778)
							(mid -0.249642 0.249642)
							(end -0.1778 0.2794)
						)
						(arc
							(start 0.1778 0.2794)
							(mid 0.249642 0.249642)
							(end 0.2794 0.1778)
						)
						(arc
							(start 0.2794 -0.1778)
							(mid 0.249642 -0.249642)
							(end 0.1778 -0.2794)
						)
					)
					(width 0)
					(fill yes)
				)
			)
		)
		(pad "2" smd custom
			(at 0 0.4445 90)
			(size 0.1397 0.1397)
			(layers "F.Cu" "F.Mask" "F.Paste")
			(net "GND")
			(options
				(clearance outline)
				(anchor circle)
			)
			(primitives
				(gr_poly
					(pts
						(arc
							(start -0.1778 -0.2794)
							(mid -0.249642 -0.249642)
							(end -0.2794 -0.1778)
						)
						(arc
							(start -0.2794 0.1778)
							(mid -0.249642 0.249642)
							(end -0.1778 0.2794)
						)
						(arc
							(start 0.1778 0.2794)
							(mid 0.249642 0.249642)
							(end 0.2794 0.1778)
						)
						(arc
							(start 0.2794 -0.1778)
							(mid 0.249642 -0.249642)
							(end 0.1778 -0.2794)
						)
					)
					(width 0)
					(fill yes)
				)
			)
		)
	)
	(footprint ""
		(layer "F.Cu")
		(at 19.431 -13.4366)
		(property "Reference" "R1"
			(at 0 0 0)
			(layer "F.SilkS")
			(hide yes)
			(effects
				(font
					(size 1.27 1.27)
				)
			)
		)
		(property "Value" "10KR2F-2-GP"
			(at 0.064008 -4.679696 0)
			(unlocked yes)
			(layer "F.Fab")
			(hide yes)
			(effects
				(font
					(size 2.54 2.54)
					(thickness 0.381)
				)
			)
		)
		(property "Device Type" "R402H16"
			(at 0.064008 -6.203696 0)
			(unlocked yes)
			(layer "F.Fab")
			(hide yes)
			(effects
				(font
					(size 2.54 2.54)
					(thickness 0.381)
				)
			)
		)
		(duplicate_pad_numbers_are_jumpers no)
		(fp_line
			(start -0.508 -0.9398)
			(end -0.508 0.9398)
			(stroke
				(width 0.1524)
				(type default)
			)
			(layer "F.SilkS")
		)
		(fp_line
			(start 0.508 -0.9398)
			(end -0.508 -0.9398)
			(stroke
				(width 0.1524)
				(type default)
			)
			(layer "F.SilkS")
		)
		(fp_rect
			(start -0.508 0.9398)
			(end 0.508 -0.9398)
			(stroke
				(width 0)
				(type default)
			)
			(fill no)
			(layer "F.CrtYd")
		)
		(fp_rect
			(start -0.508 0.9398)
			(end 0.508 -0.9398)
			(stroke
				(width 0)
				(type default)
			)
			(fill no)
			(layer "F.Fab")
		)
		(pad "1" smd custom
			(at 0 -0.4445)
			(size 0.1397 0.1397)
			(layers "F.Cu" "F.Mask" "F.Paste")
			(net "P3V3_STBY_A")
			(options
				(clearance outline)
				(anchor circle)
			)
			(primitives
				(gr_poly
					(pts
						(arc
							(start -0.1778 -0.2794)
							(mid -0.249642 -0.249642)
							(end -0.2794 -0.1778)
						)
						(arc
							(start -0.2794 0.1778)
							(mid -0.249642 0.249642)
							(end -0.1778 0.2794)
						)
						(arc
							(start 0.1778 0.2794)
							(mid 0.249642 0.249642)
							(end 0.2794 0.1778)
						)
						(arc
							(start 0.2794 -0.1778)
							(mid 0.249642 -0.249642)
							(end 0.1778 -0.2794)
						)
					)
					(width 0)
					(fill yes)
				)
			)
		)
		(pad "2" smd custom
			(at 0 0.4445)
			(size 0.1397 0.1397)
			(layers "F.Cu" "F.Mask" "F.Paste")
			(net "UART_SEL_A_MUX_R")
			(options
				(clearance outline)
				(anchor circle)
			)
			(primitives
				(gr_poly
					(pts
						(arc
							(start -0.1778 -0.2794)
							(mid -0.249642 -0.249642)
							(end -0.2794 -0.1778)
						)
						(arc
							(start -0.2794 0.1778)
							(mid -0.249642 0.249642)
							(end -0.1778 0.2794)
						)
						(arc
							(start 0.1778 0.2794)
							(mid 0.249642 0.249642)
							(end 0.2794 0.1778)
						)
						(arc
							(start 0.2794 -0.1778)
							(mid 0.249642 -0.249642)
							(end 0.1778 -0.2794)
						)
					)
					(width 0)
					(fill yes)
				)
			)
		)
	)
	(footprint ""
		(layer "F.Cu")
		(at 14.097 -30.0482 90)
		(property "Reference" "C27"
			(at 0 0 90)
			(layer "F.SilkS")
			(hide yes)
			(effects
				(font
					(size 1.27 1.27)
				)
			)
		)
		(property "Value" "SCD1U16V2KX-3GP"
			(at 1.1811 -2.7051 90)
			(unlocked yes)
			(layer "F.Fab")
			(hide yes)
			(effects
				(font
					(size 1.016 1.016)
					(thickness 0.1524)
				)
			)
		)
		(property "Device Type" "C402H22"
			(at 1.1811 -4.2291 90)
			(unlocked yes)
			(layer "F.Fab")
			(hide yes)
			(effects
				(font
					(size 1.016 1.016)
					(thickness 0.1524)
				)
			)
		)
		(duplicate_pad_numbers_are_jumpers no)
		(fp_rect
			(start -0.4318 0.9525)
			(end 0.4318 -0.9525)
			(stroke
				(width 0)
				(type default)
			)
			(fill no)
			(layer "F.CrtYd")
		)
		(fp_rect
			(start -0.4318 0.9525)
			(end 0.4318 -0.9525)
			(stroke
				(width 0)
				(type default)
			)
			(fill no)
			(layer "F.Fab")
		)
		(pad "1" smd custom
			(at 0 -0.4445 90)
			(size 0.1524 0.1524)
			(layers "F.Cu" "F.Mask" "F.Paste")
			(net "P3V3_STBY_A")
			(options
				(clearance outline)
				(anchor circle)
			)
			(primitives
				(gr_poly
					(pts
						(arc
							(start 0.3048 -0.2032)
							(mid 0.275042 -0.275042)
							(end 0.2032 -0.3048)
						)
						(arc
							(start -0.2032 -0.3048)
							(mid -0.275042 -0.275042)
							(end -0.3048 -0.2032)
						)
						(arc
							(start -0.3048 0.2032)
							(mid -0.275042 0.275042)
							(end -0.2032 0.3048)
						)
						(arc
							(start 0.2032 0.3048)
							(mid 0.275042 0.275042)
							(end 0.3048 0.2032)
						)
					)
					(width 0)
					(fill yes)
				)
			)
		)
		(pad "2" smd custom
			(at 0 0.4445 90)
			(size 0.1524 0.1524)
			(layers "F.Cu" "F.Mask" "F.Paste")
			(net "GND")
			(options
				(clearance outline)
				(anchor circle)
			)
			(primitives
				(gr_poly
					(pts
						(arc
							(start 0.3048 -0.2032)
							(mid 0.275042 -0.275042)
							(end 0.2032 -0.3048)
						)
						(arc
							(start -0.2032 -0.3048)
							(mid -0.275042 -0.275042)
							(end -0.3048 -0.2032)
						)
						(arc
							(start -0.3048 0.2032)
							(mid -0.275042 0.275042)
							(end -0.2032 0.3048)
						)
						(arc
							(start 0.2032 0.3048)
							(mid 0.275042 0.275042)
							(end 0.3048 0.2032)
						)
					)
					(width 0)
					(fill yes)
				)
			)
		)
	)
)
